FILE_TYPE = CONNECTIVITY;
{Allegro Design Entry HDL 17.2-2016 S081 (4005846) 1/11/2022}
"PAGE_NUMBER" = 204;
0"NC";
END.
